#ISCELL
  mstr_misc dns *
  *
#ISCELL
  pure_quanta quanta_title_block_c *
  *
#ISCELL
  standard offpage *
  page201_i1
#ISCELL
  pure_quanta_power universal_gnd *
  page201_i10
#CELL
  pure_quanta q_res *
  page201_i11
#CELL
  pure_quanta q_res *
  page201_i12
#ISCELL
  mstr_symbols universal_power *
  page201_i13
#CELL
  pure_quanta q_res *
  page201_i14
#CELL
  pure_quanta mpq8633bglec838z *
  page201_i15
#ISCELL
  pure_quanta_power universal_gnd *
  page201_i16
#ISCELL
  pure_quanta_power universal_gnd *
  page201_i17
#CELL
  pure_quanta q_cap *
  page201_i18
#CELL
  pure_quanta q_cap *
  page201_i19
#ISCELL
  pure_quanta_power universal_gnd *
  page201_i2
#ISCELL
  pure_quanta_power universal_gnd *
  page201_i20
#CELL
  pure_quanta q_cap *
  page201_i21
#CELL
  pure_quanta q_cap *
  page201_i22
#CELL
  pure_quanta q_cap *
  page201_i23
#CELL
  pure_quanta q_cap *
  page201_i24
#CELL
  pure_quanta q_cap *
  page201_i25
#CELL
  pure_quanta q_res *
  page201_i26
#ISCELL
  mstr_symbols universal_power *
  page201_i27
#ISCELL
  pure_quanta_power universal_gnd *
  page201_i28
#CELL
  pure_quanta q_res *
  page201_i29
#CELL
  pure_quanta q_cap *
  page201_i3
#CELL
  pure_quanta q_res *
  page201_i30
#CELL
  pure_quanta q_cap *
  page201_i31
#CELL
  pure_quanta q_res *
  page201_i32
#CELL
  pure_quanta q_inductor *
  page201_i33
#CELL
  pure_quanta q_cap *
  page201_i34
#CELL
  pure_quanta q_res *
  page201_i35
#CELL
  pure_quanta q_res *
  page201_i36
#CELL
  pure_quanta q_cap *
  page201_i37
#CELL
  pure_quanta q_cap *
  page201_i38
#CELL
  pure_quanta q_res *
  page201_i39
#CELL
  pure_quanta q_inductor *
  page201_i4
#CELL
  pure_quanta q_cap *
  page201_i40
#CELL
  pure_quanta q_cap *
  page201_i41
#CELL
  pure_quanta q_cap *
  page201_i42
#CELL
  pure_quanta q_capp *
  page201_i43
#ISCELL
  standard offpage *
  page201_i44
#ISCELL
  standard offpage *
  page201_i45
#ISCELL
  pure_quanta_power universal_gnd *
  page201_i46
#CELL
  pure_quanta q_cap *
  page201_i47
#CELL
  pure_quanta q_res *
  page201_i48
#ISCELL
  standard offpage *
  page201_i49
#ISCELL
  mstr_symbols p1v0_aux *
  page201_i5
#CELL
  pure_quanta q_res *
  page201_i50
#ISCELL
  pure_quanta_power universal_gnd *
  page201_i51
#ISCELL
  pure_quanta_power p1v0 *
  page201_i52
#CELL
  pure_quanta q_cap *
  page201_i53
#CELL
  pure_quanta q_cap *
  page201_i54
#CELL
  pure_quanta q_cap *
  page201_i55
#ISCELL
  pure_quanta_power universal_gnd *
  page201_i56
#CELL
  pure_quanta q_cap *
  page201_i57
#CELL
  pure_quanta q_res *
  page201_i58
#CELL
  pure_quanta q_cap *
  page201_i6
#ISCELL
  pure_quanta_power universal_gnd *
  page201_i7
#ISCELL
  pure_quanta_power universal_gnd *
  page201_i8
#ISCELL
  pure_quanta_power universal_gnd *
  page201_i9
